(kicad_pcb
	(version 20260206)
	(generator "pcbnew")
	(generator_version "10.0")
	(general
		(thickness 1.6)
		(legacy_teardrops no)
	)
	(paper "A4")
	(title_block
		(title "01162023_DA0F0TEBIF0_F0T_Expander_BD_F_brd_V02_OCP.brd")
		(comment 1 "Grand Teton / footprints 6657-6664 of 9728")
	)
	(layers
		(0 "F.Cu" signal "TOP")
		(4 "In1.Cu" signal "GND")
		(6 "In2.Cu" signal "VCC")
		(8 "In3.Cu" signal "VCC1")
		(10 "In4.Cu" signal "GND1")
		(12 "In5.Cu" signal "IN1")
		(14 "In6.Cu" signal "GND2")
		(16 "In7.Cu" signal "IN2")
		(18 "In8.Cu" signal "GND3")
		(20 "In9.Cu" signal "IN3")
		(22 "In10.Cu" signal "GND4")
		(24 "In11.Cu" signal "IN4")
		(26 "In12.Cu" signal "GND5")
		(28 "In13.Cu" signal "IN5")
		(30 "In14.Cu" signal "GND6")
		(32 "In15.Cu" signal "IN6")
		(34 "In16.Cu" signal "GND7")
		(2 "B.Cu" signal "BOTTOM")
		(9 "F.Adhes" user "F.Adhesive")
		(11 "B.Adhes" user "B.Adhesive")
		(13 "F.Paste" user "Package Geometry/Pastemask Top")
		(15 "B.Paste" user "Package Geometry/Pastemask Bottom")
		(5 "F.SilkS" user "Ref Des/Silkscreen Top")
		(7 "B.SilkS" user "Ref Des/Silkscreen Bottom")
		(1 "F.Mask" user "Board Geometry/Soldermask Top")
		(3 "B.Mask" user "Board Geometry/Soldermask Bottom")
		(17 "Dwgs.User" user "User.Drawings")
		(19 "Cmts.User" user "User.Comments")
		(21 "Eco1.User" user "User.Eco1")
		(23 "Eco2.User" user "User.Eco2")
		(25 "Edge.Cuts" user "Board Geometry/Outline")
		(27 "Margin" user)
		(31 "F.CrtYd" user "Package Geometry/Place Bound Top")
		(29 "B.CrtYd" user "Package Geometry/Place Bound Bottom")
		(35 "F.Fab" user "Ref Des/Assembly Top")
		(33 "B.Fab" user "Ref Des/Assembly Bottom")
	)
	(footprint ""
		(layer "F.Cu")
		(at 99.192334 -113.114582 -90)
		(property "Reference" "PD10"
			(at 4.046982 -2.205736 90)
			(unlocked yes)
			(layer "F.SilkS")
			(effects
				(font
					(size 0.7874 0.5842)
					(thickness 0.1524)
				)
				(justify left)
			)
		)
		(property "Value" ""
			(at 0 0 270)
			(layer "F.Fab")
			(effects
				(font
					(size 1.27 1.27)
				)
			)
		)
		(duplicate_pad_numbers_are_jumpers no)
		(fp_line
			(start -3.400044 1.459992)
			(end -3.400044 -1.459992)
			(stroke
				(width 0.1524)
				(type default)
			)
			(layer "F.SilkS")
		)
		(fp_line
			(start 4.107942 1.459992)
			(end -3.400044 1.459992)
			(stroke
				(width 0.1524)
				(type default)
			)
			(layer "F.SilkS")
		)
		(fp_line
			(start -3.400044 -1.459992)
			(end 4.107942 -1.459992)
			(stroke
				(width 0.1524)
				(type default)
			)
			(layer "F.SilkS")
		)
		(fp_line
			(start 4.107942 -1.459992)
			(end 4.107942 1.459992)
			(stroke
				(width 0.1524)
				(type default)
			)
			(layer "F.SilkS")
		)
		(fp_rect
			(start 4.107942 1.459992)
			(end 3.308096 -1.459992)
			(stroke
				(width 0)
				(type default)
			)
			(fill yes)
			(layer "F.SilkS")
		)
		(fp_line
			(start -2.29997 1.459992)
			(end -2.29997 -1.459992)
			(stroke
				(width 0.1)
				(type default)
			)
			(layer "F.Fab")
		)
		(fp_line
			(start 2.29997 1.459992)
			(end -2.29997 1.459992)
			(stroke
				(width 0.1)
				(type default)
			)
			(layer "F.Fab")
		)
		(fp_line
			(start -2.29997 -1.459992)
			(end 2.29997 -1.459992)
			(stroke
				(width 0.1)
				(type default)
			)
			(layer "F.Fab")
		)
		(fp_line
			(start 2.29997 -1.459992)
			(end 2.29997 1.459992)
			(stroke
				(width 0.1)
				(type default)
			)
			(layer "F.Fab")
		)
		(fp_text user "-"
			(at 5.4102 0.29845 90)
			(unlocked yes)
			(layer "F.SilkS")
			(effects
				(font
					(size 1.905 1.4224)
					(thickness 0.1524)
				)
				(justify left)
			)
		)
		(fp_text user "+"
			(at -4.7752 -0.12065 270)
			(unlocked yes)
			(layer "F.SilkS")
			(effects
				(font
					(size 1.905 1.4224)
					(thickness 0.1524)
				)
				(justify left)
			)
		)
		(fp_text user "-"
			(at 5.4102 0.29845 90)
			(unlocked yes)
			(layer "F.Fab")
			(effects
				(font
					(size 1.905 1.4224)
					(thickness 0.1524)
				)
				(justify left)
			)
		)
		(fp_text user "+"
			(at -4.7752 -0.12065 270)
			(unlocked yes)
			(layer "F.Fab")
			(effects
				(font
					(size 1.905 1.4224)
					(thickness 0.1524)
				)
				(justify left)
			)
		)
		(pad "A" smd rect
			(at -1.999996 0)
			(size 1.7018 2.5146)
			(layers "F.Cu" "F.Mask" "F.Paste")
			(net "GND")
		)
		(pad "C" smd rect
			(at 1.999996 0)
			(size 1.7018 2.5146)
			(layers "F.Cu" "F.Mask" "F.Paste")
			(net "P12V_NIC1_R")
		)
	)
	(footprint ""
		(layer "F.Cu")
		(at 376.641868 -27.006296 -90)
		(property "Reference" "PR7126"
			(at 0 0 270)
			(layer "F.SilkS")
			(hide yes)
			(effects
				(font
					(size 1.27 1.27)
				)
			)
		)
		(property "Value" ""
			(at 0 0 270)
			(layer "F.Fab")
			(effects
				(font
					(size 1.27 1.27)
				)
			)
		)
		(duplicate_pad_numbers_are_jumpers no)
		(fp_line
			(start -0.7874 0.4064)
			(end -0.7874 -0.4064)
			(stroke
				(width 0.1524)
				(type default)
			)
			(layer "F.SilkS")
		)
		(fp_line
			(start 0.7874 0.4064)
			(end -0.7874 0.4064)
			(stroke
				(width 0.1524)
				(type default)
			)
			(layer "F.SilkS")
		)
		(fp_line
			(start -0.7874 -0.4064)
			(end 0.7874 -0.4064)
			(stroke
				(width 0.1524)
				(type default)
			)
			(layer "F.SilkS")
		)
		(fp_line
			(start 0.7874 -0.4064)
			(end 0.7874 0.4064)
			(stroke
				(width 0.1524)
				(type default)
			)
			(layer "F.SilkS")
		)
		(fp_line
			(start -0.67945 0.3048)
			(end -0.67945 -0.305054)
			(stroke
				(width 0.1)
				(type default)
			)
			(layer "F.Fab")
		)
		(fp_line
			(start -0.12065 0.3048)
			(end -0.67945 0.3048)
			(stroke
				(width 0.1)
				(type default)
			)
			(layer "F.Fab")
		)
		(fp_line
			(start 0.120396 0.3048)
			(end 0.120396 0.2794)
			(stroke
				(width 0.1)
				(type default)
			)
			(layer "F.Fab")
		)
		(fp_line
			(start 0.67945 0.3048)
			(end 0.120396 0.3048)
			(stroke
				(width 0.1)
				(type default)
			)
			(layer "F.Fab")
		)
		(fp_line
			(start -0.12065 0.2794)
			(end -0.12065 0.3048)
			(stroke
				(width 0.1)
				(type default)
			)
			(layer "F.Fab")
		)
		(fp_line
			(start 0.120396 0.2794)
			(end -0.12065 0.2794)
			(stroke
				(width 0.1)
				(type default)
			)
			(layer "F.Fab")
		)
		(fp_line
			(start -0.12065 -0.2794)
			(end 0.12065 -0.2794)
			(stroke
				(width 0.1)
				(type default)
			)
			(layer "F.Fab")
		)
		(fp_line
			(start 0.12065 -0.2794)
			(end 0.12065 -0.3048)
			(stroke
				(width 0.1)
				(type default)
			)
			(layer "F.Fab")
		)
		(fp_line
			(start 0.12065 -0.3048)
			(end 0.67945 -0.3048)
			(stroke
				(width 0.1)
				(type default)
			)
			(layer "F.Fab")
		)
		(fp_line
			(start 0.67945 -0.3048)
			(end 0.67945 0.3048)
			(stroke
				(width 0.1)
				(type default)
			)
			(layer "F.Fab")
		)
		(fp_line
			(start -0.67945 -0.305054)
			(end -0.12065 -0.305054)
			(stroke
				(width 0.1)
				(type default)
			)
			(layer "F.Fab")
		)
		(fp_line
			(start -0.12065 -0.305054)
			(end -0.12065 -0.2794)
			(stroke
				(width 0.1)
				(type default)
			)
			(layer "F.Fab")
		)
		(pad "1" smd circle
			(at -0.40005 0 270)
			(size 0 0)
			(layers "F.Cu" "F.Mask" "F.Paste")
			(net "P3V3_SSD13_CO_ILIMIT")
		)
		(pad "2" smd circle
			(at 0.40005 0 270)
			(size 0 0)
			(layers "F.Cu" "F.Mask" "F.Paste")
			(net "GND")
		)
	)
	(footprint ""
		(layer "F.Cu")
		(at 132.27558 -152.71115 -90)
		(property "Reference" "R710"
			(at 0 0 270)
			(layer "F.SilkS")
			(hide yes)
			(effects
				(font
					(size 1.27 1.27)
				)
			)
		)
		(property "Value" ""
			(at 0 0 270)
			(layer "F.Fab")
			(effects
				(font
					(size 1.27 1.27)
				)
			)
		)
		(duplicate_pad_numbers_are_jumpers no)
		(fp_line
			(start -0.7874 0.4064)
			(end -0.7874 -0.4064)
			(stroke
				(width 0.1524)
				(type default)
			)
			(layer "F.SilkS")
		)
		(fp_line
			(start 0.7874 0.4064)
			(end -0.7874 0.4064)
			(stroke
				(width 0.1524)
				(type default)
			)
			(layer "F.SilkS")
		)
		(fp_line
			(start -0.7874 -0.4064)
			(end 0.7874 -0.4064)
			(stroke
				(width 0.1524)
				(type default)
			)
			(layer "F.SilkS")
		)
		(fp_line
			(start 0.7874 -0.4064)
			(end 0.7874 0.4064)
			(stroke
				(width 0.1524)
				(type default)
			)
			(layer "F.SilkS")
		)
		(fp_line
			(start -0.67945 0.3048)
			(end -0.67945 -0.305054)
			(stroke
				(width 0.1)
				(type default)
			)
			(layer "F.Fab")
		)
		(fp_line
			(start -0.12065 0.3048)
			(end -0.67945 0.3048)
			(stroke
				(width 0.1)
				(type default)
			)
			(layer "F.Fab")
		)
		(fp_line
			(start 0.120396 0.3048)
			(end 0.120396 0.2794)
			(stroke
				(width 0.1)
				(type default)
			)
			(layer "F.Fab")
		)
		(fp_line
			(start 0.67945 0.3048)
			(end 0.120396 0.3048)
			(stroke
				(width 0.1)
				(type default)
			)
			(layer "F.Fab")
		)
		(fp_line
			(start -0.12065 0.2794)
			(end -0.12065 0.3048)
			(stroke
				(width 0.1)
				(type default)
			)
			(layer "F.Fab")
		)
		(fp_line
			(start 0.120396 0.2794)
			(end -0.12065 0.2794)
			(stroke
				(width 0.1)
				(type default)
			)
			(layer "F.Fab")
		)
		(fp_line
			(start -0.12065 -0.2794)
			(end 0.12065 -0.2794)
			(stroke
				(width 0.1)
				(type default)
			)
			(layer "F.Fab")
		)
		(fp_line
			(start 0.12065 -0.2794)
			(end 0.12065 -0.3048)
			(stroke
				(width 0.1)
				(type default)
			)
			(layer "F.Fab")
		)
		(fp_line
			(start 0.12065 -0.3048)
			(end 0.67945 -0.3048)
			(stroke
				(width 0.1)
				(type default)
			)
			(layer "F.Fab")
		)
		(fp_line
			(start 0.67945 -0.3048)
			(end 0.67945 0.3048)
			(stroke
				(width 0.1)
				(type default)
			)
			(layer "F.Fab")
		)
		(fp_line
			(start -0.67945 -0.305054)
			(end -0.12065 -0.305054)
			(stroke
				(width 0.1)
				(type default)
			)
			(layer "F.Fab")
		)
		(fp_line
			(start -0.12065 -0.305054)
			(end -0.12065 -0.2794)
			(stroke
				(width 0.1)
				(type default)
			)
			(layer "F.Fab")
		)
		(pad "1" smd circle
			(at -0.40005 0 270)
			(size 0 0)
			(layers "F.Cu" "F.Mask" "F.Paste")
			(net "SMB_BIC_I2C6_MUX_NIC_ADC_R_SDA")
		)
		(pad "2" smd circle
			(at 0.40005 0 270)
			(size 0 0)
			(layers "F.Cu" "F.Mask" "F.Paste")
			(net "SMB_NIC2_ADC_SDA")
		)
	)
	(footprint ""
		(layer "F.Cu")
		(at 115.860068 -356.244906 90)
		(property "Reference" "C361"
			(at 0 0 90)
			(layer "F.SilkS")
			(hide yes)
			(effects
				(font
					(size 1.27 1.27)
				)
			)
		)
		(property "Value" ""
			(at 0 0 90)
			(layer "F.Fab")
			(effects
				(font
					(size 1.27 1.27)
				)
			)
		)
		(duplicate_pad_numbers_are_jumpers no)
		(fp_line
			(start 0.299974 -0.150114)
			(end 0.299974 0.150114)
			(stroke
				(width 0.1)
				(type default)
			)
			(layer "F.Fab")
		)
		(fp_line
			(start -0.299974 -0.150114)
			(end 0.299974 -0.150114)
			(stroke
				(width 0.1)
				(type default)
			)
			(layer "F.Fab")
		)
		(fp_line
			(start 0.299974 0.150114)
			(end -0.299974 0.150114)
			(stroke
				(width 0.1)
				(type default)
			)
			(layer "F.Fab")
		)
		(fp_line
			(start -0.299974 0.150114)
			(end -0.299974 -0.150114)
			(stroke
				(width 0.1)
				(type default)
			)
			(layer "F.Fab")
		)
		(pad "1" smd rect
			(at -0.2667 0 90)
			(size 0.3048 0.381)
			(layers "F.Cu" "F.Mask" "F.Paste")
			(net "P5E_PEX1_STN6_TX_DN<101>")
		)
		(pad "2" smd rect
			(at 0.2667 0 90)
			(size 0.3048 0.381)
			(layers "F.Cu" "F.Mask" "F.Paste")
			(net "P5E_PEX1_STN6_TX_C_DN<101>")
		)
	)
	(footprint ""
		(layer "F.Cu")
		(at 152.738328 -123.71324)
		(property "Reference" "C255"
			(at 0 0 0)
			(layer "F.SilkS")
			(hide yes)
			(effects
				(font
					(size 1.27 1.27)
				)
			)
		)
		(property "Value" ""
			(at 0 0 0)
			(layer "F.Fab")
			(effects
				(font
					(size 1.27 1.27)
				)
			)
		)
		(duplicate_pad_numbers_are_jumpers no)
		(fp_line
			(start -0.299974 -0.150114)
			(end 0.299974 -0.150114)
			(stroke
				(width 0.1)
				(type default)
			)
			(layer "F.Fab")
		)
		(fp_line
			(start -0.299974 0.150114)
			(end -0.299974 -0.150114)
			(stroke
				(width 0.1)
				(type default)
			)
			(layer "F.Fab")
		)
		(fp_line
			(start 0.299974 -0.150114)
			(end 0.299974 0.150114)
			(stroke
				(width 0.1)
				(type default)
			)
			(layer "F.Fab")
		)
		(fp_line
			(start 0.299974 0.150114)
			(end -0.299974 0.150114)
			(stroke
				(width 0.1)
				(type default)
			)
			(layer "F.Fab")
		)
		(pad "1" smd rect
			(at -0.2667 0)
			(size 0.3048 0.381)
			(layers "F.Cu" "F.Mask" "F.Paste")
			(net "P5E_PEX1_STN1_TX_DN<26>")
		)
		(pad "2" smd rect
			(at 0.2667 0)
			(size 0.3048 0.381)
			(layers "F.Cu" "F.Mask" "F.Paste")
			(net "P5E_PEX1_STN1_TX_C_DN<26>")
		)
	)
	(footprint ""
		(layer "F.Cu")
		(at 218.080844 -98.806 -90)
		(property "Reference" "R719"
			(at 0 0 270)
			(layer "F.SilkS")
			(hide yes)
			(effects
				(font
					(size 1.27 1.27)
				)
			)
		)
		(property "Value" ""
			(at 0 0 270)
			(layer "F.Fab")
			(effects
				(font
					(size 1.27 1.27)
				)
			)
		)
		(duplicate_pad_numbers_are_jumpers no)
		(fp_line
			(start -0.7874 0.4064)
			(end -0.7874 -0.4064)
			(stroke
				(width 0.1524)
				(type default)
			)
			(layer "F.SilkS")
		)
		(fp_line
			(start 0.7874 0.4064)
			(end -0.7874 0.4064)
			(stroke
				(width 0.1524)
				(type default)
			)
			(layer "F.SilkS")
		)
		(fp_line
			(start -0.7874 -0.4064)
			(end 0.7874 -0.4064)
			(stroke
				(width 0.1524)
				(type default)
			)
			(layer "F.SilkS")
		)
		(fp_line
			(start 0.7874 -0.4064)
			(end 0.7874 0.4064)
			(stroke
				(width 0.1524)
				(type default)
			)
			(layer "F.SilkS")
		)
		(fp_line
			(start -0.67945 0.3048)
			(end -0.67945 -0.305054)
			(stroke
				(width 0.1)
				(type default)
			)
			(layer "F.Fab")
		)
		(fp_line
			(start -0.12065 0.3048)
			(end -0.67945 0.3048)
			(stroke
				(width 0.1)
				(type default)
			)
			(layer "F.Fab")
		)
		(fp_line
			(start 0.120396 0.3048)
			(end 0.120396 0.2794)
			(stroke
				(width 0.1)
				(type default)
			)
			(layer "F.Fab")
		)
		(fp_line
			(start 0.67945 0.3048)
			(end 0.120396 0.3048)
			(stroke
				(width 0.1)
				(type default)
			)
			(layer "F.Fab")
		)
		(fp_line
			(start -0.12065 0.2794)
			(end -0.12065 0.3048)
			(stroke
				(width 0.1)
				(type default)
			)
			(layer "F.Fab")
		)
		(fp_line
			(start 0.120396 0.2794)
			(end -0.12065 0.2794)
			(stroke
				(width 0.1)
				(type default)
			)
			(layer "F.Fab")
		)
		(fp_line
			(start -0.12065 -0.2794)
			(end 0.12065 -0.2794)
			(stroke
				(width 0.1)
				(type default)
			)
			(layer "F.Fab")
		)
		(fp_line
			(start 0.12065 -0.2794)
			(end 0.12065 -0.3048)
			(stroke
				(width 0.1)
				(type default)
			)
			(layer "F.Fab")
		)
		(fp_line
			(start 0.12065 -0.3048)
			(end 0.67945 -0.3048)
			(stroke
				(width 0.1)
				(type default)
			)
			(layer "F.Fab")
		)
		(fp_line
			(start 0.67945 -0.3048)
			(end 0.67945 0.3048)
			(stroke
				(width 0.1)
				(type default)
			)
			(layer "F.Fab")
		)
		(fp_line
			(start -0.67945 -0.305054)
			(end -0.12065 -0.305054)
			(stroke
				(width 0.1)
				(type default)
			)
			(layer "F.Fab")
		)
		(fp_line
			(start -0.12065 -0.305054)
			(end -0.12065 -0.2794)
			(stroke
				(width 0.1)
				(type default)
			)
			(layer "F.Fab")
		)
		(pad "1" smd circle
			(at -0.40005 0 270)
			(size 0 0)
			(layers "F.Cu" "F.Mask" "F.Paste")
			(net "NIC3_ADC_A0")
		)
		(pad "2" smd circle
			(at 0.40005 0 270)
			(size 0 0)
			(layers "F.Cu" "F.Mask" "F.Paste")
			(net "GND")
		)
	)
	(footprint ""
		(layer "F.Cu")
		(at 312.21934 -153.390346 180)
		(property "Reference" "C426"
			(at 0 0 180)
			(layer "F.SilkS")
			(hide yes)
			(effects
				(font
					(size 1.27 1.27)
				)
			)
		)
		(property "Value" ""
			(at 0 0 180)
			(layer "F.Fab")
			(effects
				(font
					(size 1.27 1.27)
				)
			)
		)
		(duplicate_pad_numbers_are_jumpers no)
		(fp_line
			(start 0.299974 0.150114)
			(end -0.299974 0.150114)
			(stroke
				(width 0.1)
				(type default)
			)
			(layer "F.Fab")
		)
		(fp_line
			(start 0.299974 -0.150114)
			(end 0.299974 0.150114)
			(stroke
				(width 0.1)
				(type default)
			)
			(layer "F.Fab")
		)
		(fp_line
			(start -0.299974 0.150114)
			(end -0.299974 -0.150114)
			(stroke
				(width 0.1)
				(type default)
			)
			(layer "F.Fab")
		)
		(fp_line
			(start -0.299974 -0.150114)
			(end 0.299974 -0.150114)
			(stroke
				(width 0.1)
				(type default)
			)
			(layer "F.Fab")
		)
		(pad "1" smd rect
			(at -0.2667 0 180)
			(size 0.3048 0.381)
			(layers "F.Cu" "F.Mask" "F.Paste")
			(net "P5E_PEX2_STN0_TX_DP<14>")
		)
		(pad "2" smd rect
			(at 0.2667 0 180)
			(size 0.3048 0.381)
			(layers "F.Cu" "F.Mask" "F.Paste")
			(net "P5E_PEX2_STN0_TX_C_DP<14>")
		)
	)
	(footprint ""
		(layer "F.Cu")
		(at 146.18208 -299.391832 180)
		(property "Reference" "C3205"
			(at 0 0 180)
			(layer "F.SilkS")
			(hide yes)
			(effects
				(font
					(size 1.27 1.27)
				)
			)
		)
		(property "Value" ""
			(at 0 0 180)
			(layer "F.Fab")
			(effects
				(font
					(size 1.27 1.27)
				)
			)
		)
		(duplicate_pad_numbers_are_jumpers no)
		(fp_line
			(start 1.2954 0.5842)
			(end -1.2954 0.5842)
			(stroke
				(width 0.1524)
				(type default)
			)
			(layer "F.SilkS")
		)
		(fp_line
			(start 1.2954 -0.5842)
			(end 1.2954 0.5842)
			(stroke
				(width 0.1524)
				(type default)
			)
			(layer "F.SilkS")
		)
		(fp_line
			(start -1.2954 0.5842)
			(end -1.2954 -0.5842)
			(stroke
				(width 0.1524)
				(type default)
			)
			(layer "F.SilkS")
		)
		(fp_line
			(start -1.2954 -0.5842)
			(end 1.2954 -0.5842)
			(stroke
				(width 0.1524)
				(type default)
			)
			(layer "F.SilkS")
		)
		(fp_line
			(start 1.1938 0.4064)
			(end 0.8636 0.4064)
			(stroke
				(width 0.1)
				(type default)
			)
			(layer "F.Fab")
		)
		(fp_line
			(start 1.1938 -0.4064)
			(end 1.1938 0.4064)
			(stroke
				(width 0.1)
				(type default)
			)
			(layer "F.Fab")
		)
		(fp_line
			(start 0.8636 0.4572)
			(end -0.8636 0.4572)
			(stroke
				(width 0.1)
				(type default)
			)
			(layer "F.Fab")
		)
		(fp_line
			(start 0.8636 0.4064)
			(end 0.8636 0.4572)
			(stroke
				(width 0.1)
				(type default)
			)
			(layer "F.Fab")
		)
		(fp_line
			(start 0.8636 -0.4064)
			(end 1.1938 -0.4064)
			(stroke
				(width 0.1)
				(type default)
			)
			(layer "F.Fab")
		)
		(fp_line
			(start 0.8636 -0.4572)
			(end 0.8636 -0.4064)
			(stroke
				(width 0.1)
				(type default)
			)
			(layer "F.Fab")
		)
		(fp_line
			(start -0.8636 0.4572)
			(end -0.8636 0.4064)
			(stroke
				(width 0.1)
				(type default)
			)
			(layer "F.Fab")
		)
		(fp_line
			(start -0.8636 0.4064)
			(end -1.1938 0.4064)
			(stroke
				(width 0.1)
				(type default)
			)
			(layer "F.Fab")
		)
		(fp_line
			(start -0.8636 -0.4064)
			(end -0.8636 -0.4572)
			(stroke
				(width 0.1)
				(type default)
			)
			(layer "F.Fab")
		)
		(fp_line
			(start -0.8636 -0.4572)
			(end 0.8636 -0.4572)
			(stroke
				(width 0.1)
				(type default)
			)
			(layer "F.Fab")
		)
		(fp_line
			(start -1.1938 0.4064)
			(end -1.1938 -0.4064)
			(stroke
				(width 0.1)
				(type default)
			)
			(layer "F.Fab")
		)
		(fp_line
			(start -1.1938 -0.4064)
			(end -0.8636 -0.4064)
			(stroke
				(width 0.1)
				(type default)
			)
			(layer "F.Fab")
		)
		(pad "1" smd rect
			(at -0.7366 0 90)
			(size 0.7112 0.8128)
			(layers "F.Cu" "F.Mask" "F.Paste")
			(net "PCEPLL1_VDDA18_PEX1_R")
		)
		(pad "2" smd rect
			(at 0.7366 0 90)
			(size 0.7112 0.8128)
			(layers "F.Cu" "F.Mask" "F.Paste")
			(net "GND")
		)
	)
)
